(kicad_pcb
	(version 20240108)
	(generator "pcbnew")
	(generator_version "8.0")
	(general
		(thickness 1.62)
		(legacy_teardrops no)
	)
	(paper "A4")
	(title_block
		(title "Jetson Orin Baseboard")
		(date "2025-03-12")
		(rev "1.3.4")
		(company "Antmicro Ltd")
		(comment 1 "www.antmicro.com")
		(comment 9 "footprints 492-496 of 677")
	)
	(layers
		(0 "F.Cu" signal)
		(1 "In1.Cu" signal)
		(2 "In2.Cu" signal)
		(3 "In3.Cu" signal)
		(4 "In4.Cu" jumper)
		(5 "In5.Cu" signal)
		(6 "In6.Cu" signal)
		(31 "B.Cu" signal)
		(32 "B.Adhes" user "B.Adhesive")
		(33 "F.Adhes" user "F.Adhesive")
		(34 "B.Paste" user)
		(35 "F.Paste" user)
		(36 "B.SilkS" user "B.Silkscreen")
		(37 "F.SilkS" user "F.Silkscreen")
		(38 "B.Mask" user)
		(39 "F.Mask" user)
		(40 "Dwgs.User" user "User.Drawings")
		(41 "Cmts.User" user "User.Comments")
		(42 "Eco1.User" user "User.Eco1")
		(43 "Eco2.User" user "User.Eco2")
		(44 "Edge.Cuts" user)
		(45 "Margin" user)
		(46 "B.CrtYd" user "B.Courtyard")
		(47 "F.CrtYd" user "F.Courtyard")
		(48 "B.Fab" user)
		(49 "F.Fab" user)
	)
	(footprint "antmicro-footprints:SOT-523"
		(layer "B.Cu")
		(at 108.7 108.6 180)
		(property "Reference" "Q19"
			(at -2.14 1.09 90)
			(layer "B.SilkS")
			(effects
				(font
					(size 0.7 0.7)
					(thickness 0.15)
				)
				(justify left bottom mirror)
			)
		)
		(property "Value" "PJE138K"
			(at 0.1 -1.824 0)
			(layer "B.Fab")
			(effects
				(font
					(size 0.7 0.7)
					(thickness 0.15)
				)
				(justify left bottom mirror)
			)
		)
		(property "Footprint" "antmicro-footprints:SOT-523"
			(at 0 0 180)
			(layer "F.Fab")
			(hide yes)
			(effects
				(font
					(size 1.27 1.27)
					(thickness 0.15)
				)
			)
		)
		(property "Datasheet" "https://www.mouser.com/datasheet/2/1057/PJE138K-1876698.pdf"
			(at 0 0 180)
			(layer "F.Fab")
			(hide yes)
			(effects
				(font
					(size 1.27 1.27)
					(thickness 0.15)
				)
			)
		)
		(property "Author" "Antmicro"
			(at 217.4 217.2 0)
			(layer "B.Fab")
			(hide yes)
			(effects
				(font
					(size 1 1)
					(thickness 0.15)
				)
				(justify mirror)
			)
		)
		(property "License" "Apache-2.0"
			(at 217.4 217.2 0)
			(layer "B.Fab")
			(hide yes)
			(effects
				(font
					(size 1 1)
					(thickness 0.15)
				)
				(justify mirror)
			)
		)
		(property "MPN" "PJE138K_R1_00001"
			(at 217.4 217.2 0)
			(layer "B.Fab")
			(hide yes)
			(effects
				(font
					(size 1 1)
					(thickness 0.15)
				)
				(justify mirror)
			)
		)
		(property "Manufacturer" "PANJIT"
			(at 217.4 217.2 0)
			(layer "B.Fab")
			(hide yes)
			(effects
				(font
					(size 1 1)
					(thickness 0.15)
				)
				(justify mirror)
			)
		)
		(sheetname "USB3")
		(sheetfile "usb3.kicad_sch")
		(attr smd)
		(fp_line
			(start -0.277 0.75)
			(end -0.277 0.551)
			(stroke
				(width 0.15)
				(type solid)
			)
			(layer "B.SilkS")
		)
		(fp_line
			(start -0.277 0.551)
			(end -0.725 0.551)
			(stroke
				(width 0.15)
				(type solid)
			)
			(layer "B.SilkS")
		)
		(fp_line
			(start -0.725 0.551)
			(end -0.927 0.351)
			(stroke
				(width 0.15)
				(type solid)
			)
			(layer "B.SilkS")
		)
		(fp_line
			(start -0.927 0.351)
			(end -0.927 0.051)
			(stroke
				(width 0.15)
				(type solid)
			)
			(layer "B.SilkS")
		)
		(fp_circle
			(center -0.9652 -0.9652)
			(end -0.9152 -0.9652)
			(stroke
				(width 0.15)
				(type solid)
			)
			(fill solid)
			(layer "B.SilkS")
		)
		(fp_line
			(start 1.1 1.16)
			(end -1.12 1.16)
			(stroke
				(width 0.05)
				(type solid)
			)
			(layer "B.CrtYd")
		)
		(fp_line
			(start 1.1 -1.15)
			(end 1.1 1.16)
			(stroke
				(width 0.05)
				(type solid)
			)
			(layer "B.CrtYd")
		)
		(fp_line
			(start 1.1 -1.15)
			(end -1.12 -1.15)
			(stroke
				(width 0.05)
				(type solid)
			)
			(layer "B.CrtYd")
		)
		(fp_line
			(start -1.12 -1.15)
			(end -1.12 1.16)
			(stroke
				(width 0.05)
				(type solid)
			)
			(layer "B.CrtYd")
		)
		(fp_line
			(start 0.8 -0.424)
			(end 0.8 0.425)
			(stroke
				(width 0.15)
				(type solid)
			)
			(layer "B.Fab")
		)
		(fp_line
			(start -0.652 0.425)
			(end 0.8 0.425)
			(stroke
				(width 0.15)
				(type solid)
			)
			(layer "B.Fab")
		)
		(fp_line
			(start -0.802 0.276)
			(end -0.652 0.425)
			(stroke
				(width 0.15)
				(type solid)
			)
			(layer "B.Fab")
		)
		(fp_line
			(start -0.802 -0.424)
			(end 0.8 -0.424)
			(stroke
				(width 0.15)
				(type solid)
			)
			(layer "B.Fab")
		)
		(fp_line
			(start -0.802 -0.424)
			(end -0.802 0.276)
			(stroke
				(width 0.15)
				(type solid)
			)
			(layer "B.Fab")
		)
		(fp_circle
			(center -0.9652 -0.9652)
			(end -0.9144 -0.9652)
			(stroke
				(width 0.15)
				(type solid)
			)
			(fill none)
			(layer "B.Fab")
		)
		(fp_text user "License: Apache-2.0"
			(at -1.12 -5.024 0)
			(layer "B.Fab")
			(hide yes)
			(effects
				(font
					(size 0.7 0.7)
					(thickness 0.15)
				)
				(justify left bottom mirror)
			)
		)
		(fp_text user "${REFERENCE}"
			(at -1.12 -3.824 0)
			(layer "B.Fab")
			(hide yes)
			(effects
				(font
					(size 0.7 0.7)
					(thickness 0.15)
				)
				(justify left bottom mirror)
			)
		)
		(fp_text user "Author: Antmicro"
			(at -1.12 -6.224 0)
			(layer "B.Fab")
			(hide yes)
			(effects
				(font
					(size 0.7 0.7)
					(thickness 0.15)
				)
				(justify left bottom mirror)
			)
		)
		(pad "1" smd rect
			(at -0.5 -0.65 180)
			(size 0.4 0.51)
			(layers "B.Cu" "B.Paste" "B.Mask")
			(net 632 "Net-(Q19-G)")
			(pinfunction "G")
			(pintype "passive")
		)
		(pad "2" smd rect
			(at 0.498 -0.65 180)
			(size 0.4 0.51)
			(layers "B.Cu" "B.Paste" "B.Mask")
			(net 1 "GND")
			(pinfunction "S")
			(pintype "passive")
		)
		(pad "3" smd rect
			(at 0 0.652 180)
			(size 0.4 0.51)
			(layers "B.Cu" "B.Paste" "B.Mask")
			(net 116 "USB_FLASH_ID")
			(pinfunction "D")
			(pintype "passive")
		)
	)
	(footprint "antmicro-footprints:R_0402_1005Metric"
		(layer "B.Cu")
		(at 74.05 103.4 90)
		(descr "Resistor SMD 0402")
		(tags "resistor SMD 0402")
		(property "Reference" "R85"
			(at 5.16 1.67 -90)
			(layer "B.SilkS")
			(effects
				(font
					(size 0.7 0.7)
					(thickness 0.15)
				)
				(justify left bottom mirror)
			)
		)
		(property "Value" "R_1k_0402"
			(at 0 -1.4 -90)
			(layer "B.Fab")
			(effects
				(font
					(size 0.7 0.7)
					(thickness 0.15)
				)
				(justify left bottom mirror)
			)
		)
		(property "Footprint" "antmicro-footprints:R_0402_1005Metric"
			(at 0 0 90)
			(layer "F.Fab")
			(hide yes)
			(effects
				(font
					(size 1.27 1.27)
					(thickness 0.15)
				)
			)
		)
		(property "Datasheet" "https://www.bourns.com/docs/product-datasheets/cr.pdf"
			(at 0 0 90)
			(layer "F.Fab")
			(hide yes)
			(effects
				(font
					(size 1.27 1.27)
					(thickness 0.15)
				)
			)
		)
		(property "Author" "Antmicro"
			(at 177.45 29.35 0)
			(layer "B.Fab")
			(hide yes)
			(effects
				(font
					(size 1 1)
					(thickness 0.15)
				)
				(justify mirror)
			)
		)
		(property "License" "Apache-2.0"
			(at 177.45 29.35 0)
			(layer "B.Fab")
			(hide yes)
			(effects
				(font
					(size 1 1)
					(thickness 0.15)
				)
				(justify mirror)
			)
		)
		(property "MPN" "CR0402-FX-1001GLF"
			(at 177.45 29.35 0)
			(layer "B.Fab")
			(hide yes)
			(effects
				(font
					(size 1 1)
					(thickness 0.15)
				)
				(justify mirror)
			)
		)
		(property "Manufacturer" "Bourns"
			(at 177.45 29.35 0)
			(layer "B.Fab")
			(hide yes)
			(effects
				(font
					(size 1 1)
					(thickness 0.15)
				)
				(justify mirror)
			)
		)
		(property "Tolerance" "1%"
			(at 177.45 29.35 0)
			(layer "B.Fab")
			(hide yes)
			(effects
				(font
					(size 1 1)
					(thickness 0.15)
				)
				(justify mirror)
			)
		)
		(property "Val" "1k"
			(at 177.45 29.35 0)
			(layer "B.Fab")
			(hide yes)
			(effects
				(font
					(size 1 1)
					(thickness 0.15)
				)
				(justify mirror)
			)
		)
		(sheetname "USB Debug, DP")
		(sheetfile "usb.kicad_sch")
		(attr smd exclude_from_pos_files exclude_from_bom dnp)
		(fp_rect
			(start -0.925 0.47)
			(end 0.925 -0.47)
			(stroke
				(width 0.05)
				(type default)
			)
			(fill none)
			(layer "B.CrtYd")
		)
		(fp_rect
			(start -0.5 0.25)
			(end 0.5 -0.25)
			(stroke
				(width 0.15)
				(type solid)
			)
			(fill none)
			(layer "B.Fab")
		)
		(fp_text user "${REFERENCE}"
			(at -0.95 -3.168 -90)
			(layer "B.Fab")
			(hide yes)
			(effects
				(font
					(size 0.7 0.7)
					(thickness 0.15)
				)
				(justify left bottom mirror)
			)
		)
		(fp_text user "License: Apache-2.0"
			(at -0.95 -5.169 -90)
			(layer "B.Fab")
			(hide yes)
			(effects
				(font
					(size 0.7 0.7)
					(thickness 0.15)
				)
				(justify left bottom mirror)
			)
		)
		(fp_text user "Author: Antmicro"
			(at -0.95 -4.169 -90)
			(layer "B.Fab")
			(hide yes)
			(effects
				(font
					(size 0.7 0.7)
					(thickness 0.15)
				)
				(justify left bottom mirror)
			)
		)
		(pad "1" smd roundrect
			(at -0.48 0 90)
			(size 0.59 0.64)
			(layers "B.Cu" "B.Paste" "B.Mask")
			(roundrect_rratio 0.25)
			(net 304 "/USB Debug, DP/USBC0_I2C_EN")
			(pintype "passive")
		)
		(pad "2" smd roundrect
			(at 0.48 0 90)
			(size 0.59 0.64)
			(layers "B.Cu" "B.Paste" "B.Mask")
			(roundrect_rratio 0.25)
			(net 87 "+3V3")
			(pintype "passive")
		)
	)
	(footprint "antmicro-footprints:R_0402_1005Metric"
		(layer "B.Cu")
		(at 52.9 116.8 -90)
		(descr "Resistor SMD 0402")
		(tags "resistor SMD 0402")
		(property "Reference" "R117"
			(at 0.7 1.3 90)
			(layer "B.SilkS")
			(effects
				(font
					(size 0.7 0.7)
					(thickness 0.15)
				)
				(justify left bottom mirror)
			)
		)
		(property "Value" "R_27R_0402"
			(at 0 -1.4 90)
			(layer "B.Fab")
			(effects
				(font
					(size 0.7 0.7)
					(thickness 0.15)
				)
				(justify left bottom mirror)
			)
		)
		(property "Footprint" "antmicro-footprints:R_0402_1005Metric"
			(at 0 0 -90)
			(layer "F.Fab")
			(hide yes)
			(effects
				(font
					(size 1.27 1.27)
					(thickness 0.15)
				)
			)
		)
		(property "Datasheet" "https://www.bourns.com/docs/product-datasheets/cr.pdf"
			(at 0 0 -90)
			(layer "F.Fab")
			(hide yes)
			(effects
				(font
					(size 1.27 1.27)
					(thickness 0.15)
				)
			)
		)
		(property "Author" "Antmicro"
			(at -63.9 169.7 0)
			(layer "B.Fab")
			(hide yes)
			(effects
				(font
					(size 1 1)
					(thickness 0.15)
				)
				(justify mirror)
			)
		)
		(property "License" "Apache-2.0"
			(at -63.9 169.7 0)
			(layer "B.Fab")
			(hide yes)
			(effects
				(font
					(size 1 1)
					(thickness 0.15)
				)
				(justify mirror)
			)
		)
		(property "MPN" "CR0402-FX-27R0GLF"
			(at -63.9 169.7 0)
			(layer "B.Fab")
			(hide yes)
			(effects
				(font
					(size 1 1)
					(thickness 0.15)
				)
				(justify mirror)
			)
		)
		(property "Manufacturer" "Bourns"
			(at -63.9 169.7 0)
			(layer "B.Fab")
			(hide yes)
			(effects
				(font
					(size 1 1)
					(thickness 0.15)
				)
				(justify mirror)
			)
		)
		(property "Tolerance" "1%"
			(at -63.9 169.7 0)
			(layer "B.Fab")
			(hide yes)
			(effects
				(font
					(size 1 1)
					(thickness 0.15)
				)
				(justify mirror)
			)
		)
		(property "Val" "27R"
			(at -63.9 169.7 0)
			(layer "B.Fab")
			(hide yes)
			(effects
				(font
					(size 1 1)
					(thickness 0.15)
				)
				(justify mirror)
			)
		)
		(sheetname "USB Debug, DP")
		(sheetfile "usb.kicad_sch")
		(attr smd)
		(fp_rect
			(start -0.925 0.47)
			(end 0.925 -0.47)
			(stroke
				(width 0.05)
				(type default)
			)
			(fill none)
			(layer "B.CrtYd")
		)
		(fp_rect
			(start -0.5 0.25)
			(end 0.5 -0.25)
			(stroke
				(width 0.15)
				(type solid)
			)
			(fill none)
			(layer "B.Fab")
		)
		(fp_text user "License: Apache-2.0"
			(at -0.95 -5.169 90)
			(layer "B.Fab")
			(hide yes)
			(effects
				(font
					(size 0.7 0.7)
					(thickness 0.15)
				)
				(justify left bottom mirror)
			)
		)
		(fp_text user "${REFERENCE}"
			(at -0.95 -3.168 90)
			(layer "B.Fab")
			(hide yes)
			(effects
				(font
					(size 0.7 0.7)
					(thickness 0.15)
				)
				(justify left bottom mirror)
			)
		)
		(fp_text user "Author: Antmicro"
			(at -0.95 -4.169 90)
			(layer "B.Fab")
			(hide yes)
			(effects
				(font
					(size 0.7 0.7)
					(thickness 0.15)
				)
				(justify left bottom mirror)
			)
		)
		(pad "1" smd roundrect
			(at -0.48 0 270)
			(size 0.59 0.64)
			(layers "B.Cu" "B.Paste" "B.Mask")
			(roundrect_rratio 0.25)
			(net 312 "/USB Debug, DP/USB_FTDI_N")
			(pintype "passive")
		)
		(pad "2" smd roundrect
			(at 0.48 0 270)
			(size 0.59 0.64)
			(layers "B.Cu" "B.Paste" "B.Mask")
			(roundrect_rratio 0.25)
			(net 275 "/USB Debug, DP/USBC3_D_N")
			(pintype "passive")
		)
	)
	(footprint "antmicro-footprints:R_0402_1005Metric"
		(layer "B.Cu")
		(at 61.16 98.16 -90)
		(descr "Resistor SMD 0402")
		(tags "resistor SMD 0402")
		(property "Reference" "R246"
			(at 0.86 -0.39 90)
			(layer "B.SilkS")
			(effects
				(font
					(size 0.7 0.7)
					(thickness 0.15)
				)
				(justify left bottom mirror)
			)
		)
		(property "Value" "R_4k7_0402"
			(at 0 -1.4 90)
			(layer "B.Fab")
			(effects
				(font
					(size 0.7 0.7)
					(thickness 0.15)
				)
				(justify left bottom mirror)
			)
		)
		(property "Footprint" "antmicro-footprints:R_0402_1005Metric"
			(at 0 0 -90)
			(layer "F.Fab")
			(hide yes)
			(effects
				(font
					(size 1.27 1.27)
					(thickness 0.15)
				)
			)
		)
		(property "Datasheet" "https://www.bourns.com/docs/product-datasheets/cr.pdf"
			(at 0 0 -90)
			(layer "F.Fab")
			(hide yes)
			(effects
				(font
					(size 1.27 1.27)
					(thickness 0.15)
				)
			)
		)
		(property "Author" "Antmicro"
			(at -37 159.32 0)
			(layer "B.Fab")
			(hide yes)
			(effects
				(font
					(size 1 1)
					(thickness 0.15)
				)
				(justify mirror)
			)
		)
		(property "License" "Apache-2.0"
			(at -37 159.32 0)
			(layer "B.Fab")
			(hide yes)
			(effects
				(font
					(size 1 1)
					(thickness 0.15)
				)
				(justify mirror)
			)
		)
		(property "MPN" "CR0402-FX-4701GLF"
			(at -37 159.32 0)
			(layer "B.Fab")
			(hide yes)
			(effects
				(font
					(size 1 1)
					(thickness 0.15)
				)
				(justify mirror)
			)
		)
		(property "Manufacturer" "Bourns"
			(at -37 159.32 0)
			(layer "B.Fab")
			(hide yes)
			(effects
				(font
					(size 1 1)
					(thickness 0.15)
				)
				(justify mirror)
			)
		)
		(property "Tolerance" "1%"
			(at -37 159.32 0)
			(layer "B.Fab")
			(hide yes)
			(effects
				(font
					(size 1 1)
					(thickness 0.15)
				)
				(justify mirror)
			)
		)
		(property "Val" "4k7"
			(at -37 159.32 0)
			(layer "B.Fab")
			(hide yes)
			(effects
				(font
					(size 1 1)
					(thickness 0.15)
				)
				(justify mirror)
			)
		)
		(sheetname "USB Debug, DP")
		(sheetfile "usb.kicad_sch")
		(attr smd)
		(fp_rect
			(start -0.925 0.47)
			(end 0.925 -0.47)
			(stroke
				(width 0.05)
				(type default)
			)
			(fill none)
			(layer "B.CrtYd")
		)
		(fp_rect
			(start -0.5 0.25)
			(end 0.5 -0.25)
			(stroke
				(width 0.15)
				(type solid)
			)
			(fill none)
			(layer "B.Fab")
		)
		(fp_text user "${REFERENCE}"
			(at -0.95 -3.168 90)
			(layer "B.Fab")
			(hide yes)
			(effects
				(font
					(size 0.7 0.7)
					(thickness 0.15)
				)
				(justify left bottom mirror)
			)
		)
		(fp_text user "Author: Antmicro"
			(at -0.95 -4.169 90)
			(layer "B.Fab")
			(hide yes)
			(effects
				(font
					(size 0.7 0.7)
					(thickness 0.15)
				)
				(justify left bottom mirror)
			)
		)
		(fp_text user "License: Apache-2.0"
			(at -0.95 -5.169 90)
			(layer "B.Fab")
			(hide yes)
			(effects
				(font
					(size 0.7 0.7)
					(thickness 0.15)
				)
				(justify left bottom mirror)
			)
		)
		(pad "1" smd roundrect
			(at -0.48 0 270)
			(size 0.59 0.64)
			(layers "B.Cu" "B.Paste" "B.Mask")
			(roundrect_rratio 0.25)
			(net 87 "+3V3")
			(pintype "passive")
		)
		(pad "2" smd roundrect
			(at 0.48 0 270)
			(size 0.59 0.64)
			(layers "B.Cu" "B.Paste" "B.Mask")
			(roundrect_rratio 0.25)
			(net 303 "/USB Debug, DP/PDC_I2C1_SDA")
			(pintype "passive")
		)
	)
	(footprint "antmicro-footprints:C_0402_1005Metric"
		(layer "B.Cu")
		(at 58.55 107.05 180)
		(descr "Capacitor SMD 0402")
		(tags "capacitor SMD 0402")
		(property "Reference" "C147"
			(at -1.68 -1.36 0)
			(layer "B.SilkS")
			(effects
				(font
					(size 0.7 0.7)
					(thickness 0.15)
				)
				(justify left bottom mirror)
			)
		)
		(property "Value" "C_1u_25V_0402"
			(at 0 -1.4 0)
			(layer "B.Fab")
			(effects
				(font
					(size 0.7 0.7)
					(thickness 0.15)
				)
				(justify left bottom mirror)
			)
		)
		(property "Footprint" "antmicro-footprints:C_0402_1005Metric"
			(at 0 0 180)
			(layer "F.Fab")
			(hide yes)
			(effects
				(font
					(size 1.27 1.27)
					(thickness 0.15)
				)
			)
		)
		(property "Datasheet" "https://www.murata.com/products/productdetail?partno=GRM155R61E105KE11%23"
			(at 0 0 180)
			(layer "F.Fab")
			(hide yes)
			(effects
				(font
					(size 1.27 1.27)
					(thickness 0.15)
				)
			)
		)
		(property "Author" "Antmicro"
			(at 117.1 214.1 0)
			(layer "B.Fab")
			(hide yes)
			(effects
				(font
					(size 1 1)
					(thickness 0.15)
				)
				(justify mirror)
			)
		)
		(property "Dielectric" "X5R"
			(at 117.1 214.1 0)
			(layer "B.Fab")
			(hide yes)
			(effects
				(font
					(size 1 1)
					(thickness 0.15)
				)
				(justify mirror)
			)
		)
		(property "License" "Apache-2.0"
			(at 117.1 214.1 0)
			(layer "B.Fab")
			(hide yes)
			(effects
				(font
					(size 1 1)
					(thickness 0.15)
				)
				(justify mirror)
			)
		)
		(property "MPN" "GRM155R61E105KE11J"
			(at 117.1 214.1 0)
			(layer "B.Fab")
			(hide yes)
			(effects
				(font
					(size 1 1)
					(thickness 0.15)
				)
				(justify mirror)
			)
		)
		(property "Manufacturer" "Murata"
			(at 117.1 214.1 0)
			(layer "B.Fab")
			(hide yes)
			(effects
				(font
					(size 1 1)
					(thickness 0.15)
				)
				(justify mirror)
			)
		)
		(property "Val" "1u"
			(at 117.1 214.1 0)
			(layer "B.Fab")
			(hide yes)
			(effects
				(font
					(size 1 1)
					(thickness 0.15)
				)
				(justify mirror)
			)
		)
		(property "Voltage" "25V"
			(at 117.1 214.1 0)
			(layer "B.Fab")
			(hide yes)
			(effects
				(font
					(size 1 1)
					(thickness 0.15)
				)
				(justify mirror)
			)
		)
		(sheetname "USB Debug, DP")
		(sheetfile "usb.kicad_sch")
		(attr smd)
		(fp_rect
			(start -0.925 0.47)
			(end 0.925 -0.47)
			(stroke
				(width 0.05)
				(type default)
			)
			(fill none)
			(layer "B.CrtYd")
		)
		(fp_line
			(start 0.504 0.25)
			(end -0.494 0.25)
			(stroke
				(width 0.15)
				(type solid)
			)
			(layer "B.Fab")
		)
		(fp_line
			(start 0.504 -0.248)
			(end 0.504 0.25)
			(stroke
				(width 0.15)
				(type solid)
			)
			(layer "B.Fab")
		)
		(fp_line
			(start -0.494 0.25)
			(end -0.494 -0.248)
			(stroke
				(width 0.15)
				(type solid)
			)
			(layer "B.Fab")
		)
		(fp_line
			(start -0.494 -0.248)
			(end 0.504 -0.248)
			(stroke
				(width 0.15)
				(type solid)
			)
			(layer "B.Fab")
		)
		(fp_text user "Author: Antmicro"
			(at -0.932 -4.17 0)
			(layer "B.Fab")
			(hide yes)
			(effects
				(font
					(size 0.7 0.7)
					(thickness 0.15)
				)
				(justify left bottom mirror)
			)
		)
		(fp_text user "License: Apache-2.0"
			(at -0.932 -5.17 0)
			(layer "B.Fab")
			(hide yes)
			(effects
				(font
					(size 0.7 0.7)
					(thickness 0.15)
				)
				(justify left bottom mirror)
			)
		)
		(fp_text user "${REFERENCE}"
			(at -0.932 -3.168 0)
			(layer "B.Fab")
			(hide yes)
			(effects
				(font
					(size 0.7 0.7)
					(thickness 0.15)
				)
				(justify left bottom mirror)
			)
		)
		(pad "1" smd roundrect
			(at -0.48 0 180)
			(size 0.59 0.64)
			(layers "B.Cu" "B.Paste" "B.Mask")
			(roundrect_rratio 0.25)
			(net 196 "/USB Debug, DP/USBC3_VBUS")
			(pintype "passive")
		)
		(pad "2" smd roundrect
			(at 0.48 0 180)
			(size 0.59 0.64)
			(layers "B.Cu" "B.Paste" "B.Mask")
			(roundrect_rratio 0.25)
			(net 1 "GND")
			(pintype "passive")
		)
	)
)
